# T6G (Grand Teton) — schematic netlist excerpt (pin names and nets, part order shuffled) for the footprints in the layout excerpt that follows; sources: Cadence DE-HDL packaged netlist, KiCad conversion of 04192023_DAF0TMB3IC0_F0TG_MB_C_brd_V02_OCP.brd

C815  Q_CAP_DIFFBUS  DIFF BUS_0.22UF 6.3V 20% X6S  pkg C0201  page 65 : \1\ = P5E_CPU1_P0_TX_C_DP<11> ; \2\ = P5E_CPU1_P0_TX_DP<11>
R686  Q_RES  49.9 1% CHIP  pkg 0201LF  page 309 : A = SMB_RT_CPU0_P3_ROM_MUX_1D_SDA ; B = SMB_RT_CPU0_P3_ROM_MUX_1D_R_SDA
D79  Q_LED  IC  pkg SMLF  page 255 : A = LED_PWRGD_PVDD18_S5_P0_R ; C = LED_PWRGD_PVDD18_S5_P0_D

(kicad_pcb
	(version 20260206)
	(generator "pcbnew")
	(generator_version "10.0")
	(general
		(thickness 1.6)
		(legacy_teardrops no)
	)
	(paper "A4")
	(title_block
		(title "04192023_DAF0TMB3IC0_F0TG_MB_C_brd_V02_OCP.brd")
		(comment 1 "Grand Teton / footprints 3811-3813 of 8354")
	)
	(layers
		(0 "F.Cu" signal "TOP")
		(4 "In1.Cu" signal "GND")
		(6 "In2.Cu" signal "IN1")
		(8 "In3.Cu" signal "GND1")
		(10 "In4.Cu" signal "IN2")
		(12 "In5.Cu" signal "GND2")
		(14 "In6.Cu" signal "IN3")
		(16 "In7.Cu" signal "GND3")
		(18 "In8.Cu" signal "VCC")
		(20 "In9.Cu" signal "VCC1")
		(22 "In10.Cu" signal "GND4")
		(24 "In11.Cu" signal "IN4")
		(26 "In12.Cu" signal "GND5")
		(28 "In13.Cu" signal "IN5")
		(30 "In14.Cu" signal "GND6")
		(32 "In15.Cu" signal "IN6")
		(34 "In16.Cu" signal "GND7")
		(2 "B.Cu" signal "BOTTOM")
		(9 "F.Adhes" user "F.Adhesive")
		(11 "B.Adhes" user "B.Adhesive")
		(13 "F.Paste" user "Package Geometry/Pastemask Top")
		(15 "B.Paste" user "Package Geometry/Pastemask Bottom")
		(5 "F.SilkS" user "Ref Des/Silkscreen Top")
		(7 "B.SilkS" user "Ref Des/Silkscreen Bottom")
		(1 "F.Mask" user "Board Geometry/Soldermask Top")
		(3 "B.Mask" user "Board Geometry/Soldermask Bottom")
		(17 "Dwgs.User" user "User.Drawings")
		(19 "Cmts.User" user "User.Comments")
		(21 "Eco1.User" user "User.Eco1")
		(23 "Eco2.User" user "User.Eco2")
		(25 "Edge.Cuts" user "Board Geometry/Outline")
		(27 "Margin" user)
		(31 "F.CrtYd" user "Package Geometry/Place Bound Top")
		(29 "B.CrtYd" user "Package Geometry/Place Bound Bottom")
		(35 "F.Fab" user "Ref Des/Assembly Top")
		(33 "B.Fab" user "Ref Des/Assembly Bottom")
	)
	(footprint ""
		(layer "F.Cu")
		(at 63.411354 -373.03583 -90)
		(property "Reference" "C815"
			(at 0 0 270)
			(layer "F.SilkS")
			(hide yes)
			(effects
				(font
					(size 1.27 1.27)
				)
			)
		)
		(property "Value" ""
			(at 0 0 270)
			(layer "F.Fab")
			(effects
				(font
					(size 1.27 1.27)
				)
			)
		)
		(duplicate_pad_numbers_are_jumpers no)
		(fp_line
			(start -0.299974 0.150114)
			(end -0.299974 -0.150114)
			(stroke
				(width 0.1)
				(type default)
			)
			(layer "F.Fab")
		)
		(fp_line
			(start 0.299974 0.150114)
			(end -0.299974 0.150114)
			(stroke
				(width 0.1)
				(type default)
			)
			(layer "F.Fab")
		)
		(fp_line
			(start -0.299974 -0.150114)
			(end 0.299974 -0.150114)
			(stroke
				(width 0.1)
				(type default)
			)
			(layer "F.Fab")
		)
		(fp_line
			(start 0.299974 -0.150114)
			(end 0.299974 0.150114)
			(stroke
				(width 0.1)
				(type default)
			)
			(layer "F.Fab")
		)
		(pad "1" smd rect
			(at -0.2667 0 270)
			(size 0.3048 0.381)
			(layers "F.Cu" "F.Mask" "F.Paste")
			(net "P5E_CPU1_P0_TX_C_DP<11>")
		)
		(pad "2" smd rect
			(at 0.2667 0 270)
			(size 0.3048 0.381)
			(layers "F.Cu" "F.Mask" "F.Paste")
			(net "P5E_CPU1_P0_TX_DP<11>")
		)
	)
	(footprint ""
		(layer "F.Cu")
		(at 365.794798 -427.39691 180)
		(property "Reference" "R686"
			(at 0 0 180)
			(layer "F.SilkS")
			(hide yes)
			(effects
				(font
					(size 1.27 1.27)
				)
			)
		)
		(property "Value" ""
			(at 0 0 180)
			(layer "F.Fab")
			(effects
				(font
					(size 1.27 1.27)
				)
			)
		)
		(duplicate_pad_numbers_are_jumpers no)
		(fp_line
			(start 0.32512 0.175006)
			(end -0.32512 0.175006)
			(stroke
				(width 0.1)
				(type default)
			)
			(layer "F.Fab")
		)
		(fp_line
			(start 0.32512 -0.175006)
			(end 0.32512 0.175006)
			(stroke
				(width 0.1)
				(type default)
			)
			(layer "F.Fab")
		)
		(fp_line
			(start -0.32512 0.175006)
			(end -0.32512 -0.175006)
			(stroke
				(width 0.1)
				(type default)
			)
			(layer "F.Fab")
		)
		(fp_line
			(start -0.32512 -0.175006)
			(end 0.32512 -0.175006)
			(stroke
				(width 0.1)
				(type default)
			)
			(layer "F.Fab")
		)
		(pad "1" smd rect
			(at -0.2667 0 180)
			(size 0.3048 0.381)
			(layers "F.Cu" "F.Mask" "F.Paste")
			(net "SMB_RT_CPU0_P3_ROM_MUX_1D_SDA")
		)
		(pad "2" smd rect
			(at 0.2667 0)
			(size 0.3048 0.381)
			(layers "F.Cu" "F.Mask" "F.Paste")
			(net "SMB_RT_CPU0_P3_ROM_MUX_1D_R_SDA")
		)
	)
	(footprint ""
		(layer "F.Cu")
		(at 334.795876 -70.098412 90)
		(property "Reference" "D79"
			(at -3.934714 -0.691642 90)
			(unlocked yes)
			(layer "F.SilkS")
			(effects
				(font
					(size 0.7874 0.5842)
					(thickness 0.1524)
				)
				(justify left)
			)
		)
		(property "Value" ""
			(at 0 0 90)
			(layer "F.Fab")
			(effects
				(font
					(size 1.27 1.27)
				)
			)
		)
		(duplicate_pad_numbers_are_jumpers no)
		(fp_line
			(start 1.16078 -0.4826)
			(end 1.16078 0.4826)
			(stroke
				(width 0.1524)
				(type default)
			)
			(layer "F.SilkS")
		)
		(fp_line
			(start 1.03378 -0.4826)
			(end 1.03378 0.4826)
			(stroke
				(width 0.1524)
				(type default)
			)
			(layer "F.SilkS")
		)
		(fp_line
			(start 0.90678 -0.4826)
			(end 0.90678 0.4826)
			(stroke
				(width 0.1524)
				(type default)
			)
			(layer "F.SilkS")
		)
		(fp_line
			(start -0.64008 -0.4826)
			(end 1.16078 -0.4826)
			(stroke
				(width 0.1524)
				(type default)
			)
			(layer "F.SilkS")
		)
		(fp_line
			(start -0.79248 -0.4826)
			(end 1.03378 -0.4826)
			(stroke
				(width 0.1524)
				(type default)
			)
			(layer "F.SilkS")
		)
		(fp_line
			(start -0.89408 -0.4826)
			(end 0.90678 -0.4826)
			(stroke
				(width 0.1524)
				(type default)
			)
			(layer "F.SilkS")
		)
		(fp_line
			(start 1.16078 0.4826)
			(end -0.64008 0.4826)
			(stroke
				(width 0.1524)
				(type default)
			)
			(layer "F.SilkS")
		)
		(fp_line
			(start 1.03378 0.4826)
			(end -0.79248 0.4826)
			(stroke
				(width 0.1524)
				(type default)
			)
			(layer "F.SilkS")
		)
		(fp_line
			(start 0.90678 0.4826)
			(end -0.90678 0.4826)
			(stroke
				(width 0.1524)
				(type default)
			)
			(layer "F.SilkS")
		)
		(fp_line
			(start -0.90678 0.4826)
			(end -0.90678 -0.4699)
			(stroke
				(width 0.1524)
				(type default)
			)
			(layer "F.SilkS")
		)
		(fp_line
			(start 0.499872 -0.249936)
			(end 0.499872 0.249936)
			(stroke
				(width 0.1)
				(type default)
			)
			(layer "F.Fab")
		)
		(fp_line
			(start -0.499872 -0.249936)
			(end 0.499872 -0.249936)
			(stroke
				(width 0.1)
				(type default)
			)
			(layer "F.Fab")
		)
		(fp_line
			(start 0.499872 0.249936)
			(end -0.499872 0.249936)
			(stroke
				(width 0.1)
				(type default)
			)
			(layer "F.Fab")
		)
		(fp_line
			(start -0.499872 0.249936)
			(end -0.499872 -0.249936)
			(stroke
				(width 0.1)
				(type default)
			)
			(layer "F.Fab")
		)
		(pad "A" smd rect
			(at -0.47498 0 90)
			(size 0.6096 0.7112)
			(layers "F.Cu" "F.Mask" "F.Paste")
			(net "LED_PWRGD_PVDD18_S5_P0_R")
		)
		(pad "C" smd rect
			(at 0.47498 0 90)
			(size 0.6096 0.7112)
			(layers "F.Cu" "F.Mask" "F.Paste")
			(net "LED_PWRGD_PVDD18_S5_P0_D")
		)
	)
)
